(kicad_pcb
	(version 20260206)
	(generator "pcbnew")
	(generator_version "10.0")
	(general
		(thickness 1.6)
		(legacy_teardrops no)
	)
	(paper "A4")
	(title_block
		(title "fcb — Lightning_FCB_BRD.brd")
		(comment 1 "Lightning (Wiwynn / Facebook NVMe JBOF) / footprints 343-349 of 495")
	)
	(layers
		(0 "F.Cu" signal "TOP")
		(4 "In1.Cu" signal "L2GND")
		(6 "In2.Cu" signal "L3VCC")
		(2 "B.Cu" signal "BOTTOM")
		(9 "F.Adhes" user "F.Adhesive")
		(11 "B.Adhes" user "B.Adhesive")
		(13 "F.Paste" user "Package Geometry/Pastemask Top")
		(15 "B.Paste" user "Package Geometry/Pastemask Bottom")
		(5 "F.SilkS" user "Ref Des/Silkscreen Top")
		(7 "B.SilkS" user "Ref Des/Silkscreen Bottom")
		(1 "F.Mask" user "Board Geometry/Soldermask Top")
		(3 "B.Mask" user "Board Geometry/Soldermask Bottom")
		(17 "Dwgs.User" user "User.Drawings")
		(19 "Cmts.User" user "User.Comments")
		(21 "Eco1.User" user "User.Eco1")
		(23 "Eco2.User" user "User.Eco2")
		(25 "Edge.Cuts" user "Board Geometry/Outline")
		(27 "Margin" user)
		(31 "F.CrtYd" user "Package Geometry/Place Bound Top")
		(29 "B.CrtYd" user "Package Geometry/Place Bound Bottom")
		(35 "F.Fab" user "Ref Des/Assembly Top")
		(33 "B.Fab" user "Ref Des/Assembly Bottom")
	)
	(footprint ""
		(layer "F.Cu")
		(at 16.2814 -231.4194)
		(property "Reference" "R115"
			(at 0 0 0)
			(layer "F.SilkS")
			(hide yes)
			(effects
				(font
					(size 1.27 1.27)
				)
			)
		)
		(property "Value" "2KR2F-3-GP"
			(at 0.064008 -3.993896 0)
			(unlocked yes)
			(layer "F.Fab")
			(hide yes)
			(effects
				(font
					(size 1.016 1.016)
					(thickness 0.1524)
				)
			)
		)
		(property "Device Type" "R402H16"
			(at 0.064008 -5.517896 0)
			(unlocked yes)
			(layer "F.Fab")
			(hide yes)
			(effects
				(font
					(size 1.016 1.016)
					(thickness 0.1524)
				)
			)
		)
		(duplicate_pad_numbers_are_jumpers no)
		(fp_line
			(start -0.508 -0.9398)
			(end -0.508 0.9398)
			(stroke
				(width 0.1524)
				(type default)
			)
			(layer "F.SilkS")
		)
		(fp_line
			(start 0.508 -0.9398)
			(end -0.508 -0.9398)
			(stroke
				(width 0.1524)
				(type default)
			)
			(layer "F.SilkS")
		)
		(fp_rect
			(start -0.508 0.9398)
			(end 0.508 -0.9398)
			(stroke
				(width 0)
				(type default)
			)
			(fill no)
			(layer "F.CrtYd")
		)
		(fp_rect
			(start -0.508 0.9398)
			(end 0.508 -0.9398)
			(stroke
				(width 0)
				(type default)
			)
			(fill no)
			(layer "F.Fab")
		)
		(pad "1" smd custom
			(at 0 -0.4445)
			(size 0.1397 0.1397)
			(layers "F.Cu" "F.Mask" "F.Paste")
			(net "LED_DR_LED3")
			(options
				(clearance outline)
				(anchor circle)
			)
			(primitives
				(gr_poly
					(pts
						(arc
							(start -0.1778 -0.2794)
							(mid -0.249642 -0.249642)
							(end -0.2794 -0.1778)
						)
						(arc
							(start -0.2794 0.1778)
							(mid -0.249642 0.249642)
							(end -0.1778 0.2794)
						)
						(arc
							(start 0.1778 0.2794)
							(mid 0.249642 0.249642)
							(end 0.2794 0.1778)
						)
						(arc
							(start 0.2794 -0.1778)
							(mid 0.249642 -0.249642)
							(end 0.1778 -0.2794)
						)
					)
					(width 0)
					(fill yes)
				)
			)
		)
		(pad "2" smd custom
			(at 0 0.4445)
			(size 0.1397 0.1397)
			(layers "F.Cu" "F.Mask" "F.Paste")
			(net "LED_DR_LED3_B")
			(options
				(clearance outline)
				(anchor circle)
			)
			(primitives
				(gr_poly
					(pts
						(arc
							(start -0.1778 -0.2794)
							(mid -0.249642 -0.249642)
							(end -0.2794 -0.1778)
						)
						(arc
							(start -0.2794 0.1778)
							(mid -0.249642 0.249642)
							(end -0.1778 0.2794)
						)
						(arc
							(start 0.1778 0.2794)
							(mid 0.249642 0.249642)
							(end 0.2794 0.1778)
						)
						(arc
							(start 0.2794 -0.1778)
							(mid 0.249642 -0.249642)
							(end 0.1778 -0.2794)
						)
					)
					(width 0)
					(fill yes)
				)
			)
		)
	)
	(footprint ""
		(layer "F.Cu")
		(at 26.8732 -357.6574 -90)
		(property "Reference" "R367"
			(at 0 0 270)
			(layer "F.SilkS")
			(hide yes)
			(effects
				(font
					(size 1.27 1.27)
				)
			)
		)
		(property "Value" "10KR2F-2-GP"
			(at 0.064008 -3.993896 270)
			(unlocked yes)
			(layer "F.Fab")
			(hide yes)
			(effects
				(font
					(size 1.016 1.016)
					(thickness 0.1524)
				)
			)
		)
		(property "Device Type" "R402H16"
			(at 0.064008 -5.517896 270)
			(unlocked yes)
			(layer "F.Fab")
			(hide yes)
			(effects
				(font
					(size 1.016 1.016)
					(thickness 0.1524)
				)
			)
		)
		(duplicate_pad_numbers_are_jumpers no)
		(fp_line
			(start -0.508 -0.9398)
			(end -0.508 0.9398)
			(stroke
				(width 0.1524)
				(type default)
			)
			(layer "F.SilkS")
		)
		(fp_line
			(start 0.508 -0.9398)
			(end -0.508 -0.9398)
			(stroke
				(width 0.1524)
				(type default)
			)
			(layer "F.SilkS")
		)
		(fp_rect
			(start -0.508 0.9398)
			(end 0.508 -0.9398)
			(stroke
				(width 0)
				(type default)
			)
			(fill no)
			(layer "F.CrtYd")
		)
		(fp_rect
			(start -0.508 0.9398)
			(end 0.508 -0.9398)
			(stroke
				(width 0)
				(type default)
			)
			(fill no)
			(layer "F.Fab")
		)
		(pad "1" smd custom
			(at 0 -0.4445 270)
			(size 0.1397 0.1397)
			(layers "F.Cu" "F.Mask" "F.Paste")
			(net "P3V3")
			(options
				(clearance outline)
				(anchor circle)
			)
			(primitives
				(gr_poly
					(pts
						(arc
							(start -0.1778 -0.2794)
							(mid -0.249642 -0.249642)
							(end -0.2794 -0.1778)
						)
						(arc
							(start -0.2794 0.1778)
							(mid -0.249642 0.249642)
							(end -0.1778 0.2794)
						)
						(arc
							(start 0.1778 0.2794)
							(mid 0.249642 0.249642)
							(end 0.2794 0.1778)
						)
						(arc
							(start 0.2794 -0.1778)
							(mid 0.249642 -0.249642)
							(end 0.1778 -0.2794)
						)
					)
					(width 0)
					(fill yes)
				)
			)
		)
		(pad "2" smd custom
			(at 0 0.4445 270)
			(size 0.1397 0.1397)
			(layers "F.Cu" "F.Mask" "F.Paste")
			(net "TEMP_ALM#_G")
			(options
				(clearance outline)
				(anchor circle)
			)
			(primitives
				(gr_poly
					(pts
						(arc
							(start -0.1778 -0.2794)
							(mid -0.249642 -0.249642)
							(end -0.2794 -0.1778)
						)
						(arc
							(start -0.2794 0.1778)
							(mid -0.249642 0.249642)
							(end -0.1778 0.2794)
						)
						(arc
							(start 0.1778 0.2794)
							(mid 0.249642 0.249642)
							(end 0.2794 0.1778)
						)
						(arc
							(start 0.2794 -0.1778)
							(mid 0.249642 -0.249642)
							(end 0.1778 -0.2794)
						)
					)
					(width 0)
					(fill yes)
				)
			)
		)
	)
	(footprint ""
		(layer "F.Cu")
		(at 24.384 -237.871)
		(property "Reference" "PC43"
			(at 0 0 0)
			(layer "F.SilkS")
			(hide yes)
			(effects
				(font
					(size 1.27 1.27)
				)
			)
		)
		(property "Value" "SC22U16V6MX-GP"
			(at -0.0762 -5.1308 0)
			(unlocked yes)
			(layer "F.Fab")
			(hide yes)
			(effects
				(font
					(size 1.016 1.016)
					(thickness 0.1524)
				)
			)
		)
		(property "Device Type" "C1206H71"
			(at -0.127 -6.6548 0)
			(unlocked yes)
			(layer "F.Fab")
			(hide yes)
			(effects
				(font
					(size 1.016 1.016)
					(thickness 0.1524)
				)
			)
		)
		(duplicate_pad_numbers_are_jumpers no)
		(fp_line
			(start -1.016 -2.2352)
			(end 1.016 -2.2352)
			(stroke
				(width 0.1524)
				(type default)
			)
			(layer "F.SilkS")
		)
		(fp_line
			(start -1.016 -0.8382)
			(end -1.016 -2.2352)
			(stroke
				(width 0.1524)
				(type default)
			)
			(layer "F.SilkS")
		)
		(fp_line
			(start -1.016 2.2352)
			(end -1.016 0.8382)
			(stroke
				(width 0.1524)
				(type default)
			)
			(layer "F.SilkS")
		)
		(fp_line
			(start 1.016 -2.2352)
			(end 1.016 -0.8382)
			(stroke
				(width 0.1524)
				(type default)
			)
			(layer "F.SilkS")
		)
		(fp_line
			(start 1.016 0.8382)
			(end 1.016 2.2352)
			(stroke
				(width 0.1524)
				(type default)
			)
			(layer "F.SilkS")
		)
		(fp_line
			(start 1.016 2.2352)
			(end -1.016 2.2352)
			(stroke
				(width 0.1524)
				(type default)
			)
			(layer "F.SilkS")
		)
		(fp_rect
			(start -1.0922 2.3114)
			(end 1.0922 -2.3114)
			(stroke
				(width 0)
				(type default)
			)
			(fill no)
			(layer "F.CrtYd")
		)
		(fp_poly
			(pts
				(xy 1.0922 -2.3114) (xy 1.0922 2.3114) (xy -1.0922 2.3114) (xy -1.0922 -2.3114)
			)
			(stroke
				(width 0)
				(type default)
			)
			(fill no)
			(layer "F.Fab")
		)
		(pad "1" smd rect
			(at 0 -1.397)
			(size 1.651 1.27)
			(layers "F.Cu" "F.Mask" "F.Paste")
			(net "P3V3_LX_COPPER")
		)
		(pad "2" smd rect
			(at 0 1.397)
			(size 1.651 1.27)
			(layers "F.Cu" "F.Mask" "F.Paste")
			(net "GND")
		)
	)
	(footprint ""
		(layer "F.Cu")
		(at 30.734 -381 180)
		(property "Reference" "PR20"
			(at 0 0 180)
			(layer "F.SilkS")
			(hide yes)
			(effects
				(font
					(size 1.27 1.27)
				)
			)
		)
		(property "Value" "10R2F-L-GP"
			(at 0.064008 -3.993896 180)
			(unlocked yes)
			(layer "F.Fab")
			(hide yes)
			(effects
				(font
					(size 1.016 1.016)
					(thickness 0.1524)
				)
			)
		)
		(property "Device Type" "R402H14"
			(at 0.064008 -5.517896 180)
			(unlocked yes)
			(layer "F.Fab")
			(hide yes)
			(effects
				(font
					(size 1.016 1.016)
					(thickness 0.1524)
				)
			)
		)
		(duplicate_pad_numbers_are_jumpers no)
		(fp_line
			(start 0.508 -0.9398)
			(end -0.508 -0.9398)
			(stroke
				(width 0.1524)
				(type default)
			)
			(layer "F.SilkS")
		)
		(fp_line
			(start -0.508 -0.9398)
			(end -0.508 0.9398)
			(stroke
				(width 0.1524)
				(type default)
			)
			(layer "F.SilkS")
		)
		(fp_rect
			(start -0.508 0.9398)
			(end 0.508 -0.9398)
			(stroke
				(width 0)
				(type default)
			)
			(fill no)
			(layer "F.CrtYd")
		)
		(fp_rect
			(start -0.508 0.9398)
			(end 0.508 -0.9398)
			(stroke
				(width 0)
				(type default)
			)
			(fill no)
			(layer "F.Fab")
		)
		(pad "1" smd custom
			(at 0 -0.4445 180)
			(size 0.1397 0.1397)
			(layers "F.Cu" "F.Mask" "F.Paste")
			(net "ADM1276_SENSE+")
			(options
				(clearance outline)
				(anchor circle)
			)
			(primitives
				(gr_poly
					(pts
						(arc
							(start -0.1778 -0.2794)
							(mid -0.249642 -0.249642)
							(end -0.2794 -0.1778)
						)
						(arc
							(start -0.2794 0.1778)
							(mid -0.249642 0.249642)
							(end -0.1778 0.2794)
						)
						(arc
							(start 0.1778 0.2794)
							(mid 0.249642 0.249642)
							(end 0.2794 0.1778)
						)
						(arc
							(start 0.2794 -0.1778)
							(mid 0.249642 -0.249642)
							(end 0.1778 -0.2794)
						)
					)
					(width 0)
					(fill yes)
				)
			)
		)
		(pad "2" smd custom
			(at 0 0.4445 180)
			(size 0.1397 0.1397)
			(layers "F.Cu" "F.Mask" "F.Paste")
			(net "SENSE+_R1")
			(options
				(clearance outline)
				(anchor circle)
			)
			(primitives
				(gr_poly
					(pts
						(arc
							(start -0.1778 -0.2794)
							(mid -0.249642 -0.249642)
							(end -0.2794 -0.1778)
						)
						(arc
							(start -0.2794 0.1778)
							(mid -0.249642 0.249642)
							(end -0.1778 0.2794)
						)
						(arc
							(start 0.1778 0.2794)
							(mid 0.249642 0.249642)
							(end 0.2794 0.1778)
						)
						(arc
							(start 0.2794 -0.1778)
							(mid 0.249642 -0.249642)
							(end 0.1778 -0.2794)
						)
					)
					(width 0)
					(fill yes)
				)
			)
		)
	)
	(footprint ""
		(layer "F.Cu")
		(at 31.75 -357.048816)
		(property "Reference" "Q49"
			(at 0 0 0)
			(layer "F.SilkS")
			(hide yes)
			(effects
				(font
					(size 1.27 1.27)
				)
			)
		)
		(property "Value" "2N7002-11-GP"
			(at 0.127 -8.9662 0)
			(unlocked yes)
			(layer "F.Fab")
			(hide yes)
			(effects
				(font
					(size 1.016 1.016)
					(thickness 0.1524)
				)
			)
		)
		(property "Device Type" "SOT23DGS2D4H44"
			(at 0.127 -10.4902 0)
			(unlocked yes)
			(layer "F.Fab")
			(hide yes)
			(effects
				(font
					(size 1.016 1.016)
					(thickness 0.1524)
				)
			)
		)
		(duplicate_pad_numbers_are_jumpers no)
		(fp_line
			(start -1.651 -1.778)
			(end -1.651 1.778)
			(stroke
				(width 0.1524)
				(type default)
			)
			(layer "F.SilkS")
		)
		(fp_line
			(start -1.651 1.778)
			(end 1.651 1.778)
			(stroke
				(width 0.1524)
				(type default)
			)
			(layer "F.SilkS")
		)
		(fp_line
			(start 1.651 -1.778)
			(end -1.651 -1.778)
			(stroke
				(width 0.1524)
				(type default)
			)
			(layer "F.SilkS")
		)
		(fp_line
			(start 1.651 1.778)
			(end 1.651 -1.778)
			(stroke
				(width 0.1524)
				(type default)
			)
			(layer "F.SilkS")
		)
		(fp_poly
			(pts
				(xy -1.778 1.8796) (xy -1.778 -1.8796) (xy 1.778 -1.8796) (xy 1.778 1.8796)
			)
			(stroke
				(width 0)
				(type default)
			)
			(fill no)
			(layer "F.CrtYd")
		)
		(fp_poly
			(pts
				(xy -1.778 1.8796) (xy -1.778 -1.8796) (xy 1.778 -1.8796) (xy 1.778 1.8796)
			)
			(stroke
				(width 0)
				(type default)
			)
			(fill no)
			(layer "F.Fab")
		)
		(pad "D" smd custom
			(at 0 -0.9525)
			(size 0.1905 0.1905)
			(layers "F.Cu" "F.Mask" "F.Paste")
			(net "ADM1276_EN")
			(options
				(clearance outline)
				(anchor circle)
			)
			(primitives
				(gr_poly
					(pts
						(arc
							(start -0.1778 0.5715)
							(mid -0.321484 0.511984)
							(end -0.381 0.3683)
						)
						(arc
							(start -0.381 -0.3683)
							(mid -0.321484 -0.511984)
							(end -0.1778 -0.5715)
						)
						(arc
							(start 0.1778 -0.5715)
							(mid 0.321484 -0.511984)
							(end 0.381 -0.3683)
						)
						(arc
							(start 0.381 0.3683)
							(mid 0.321484 0.511984)
							(end 0.1778 0.5715)
						)
					)
					(width 0)
					(fill yes)
				)
			)
		)
		(pad "G" smd custom
			(at -0.98425 0.9525)
			(size 0.1905 0.1905)
			(layers "F.Cu" "F.Mask" "F.Paste")
			(net "OTP_RETRY_G")
			(options
				(clearance outline)
				(anchor circle)
			)
			(primitives
				(gr_poly
					(pts
						(arc
							(start -0.1778 0.5715)
							(mid -0.321484 0.511984)
							(end -0.381 0.3683)
						)
						(arc
							(start -0.381 -0.3683)
							(mid -0.321484 -0.511984)
							(end -0.1778 -0.5715)
						)
						(arc
							(start 0.1778 -0.5715)
							(mid 0.321484 -0.511984)
							(end 0.381 -0.3683)
						)
						(arc
							(start 0.381 0.3683)
							(mid 0.321484 0.511984)
							(end 0.1778 0.5715)
						)
					)
					(width 0)
					(fill yes)
				)
			)
		)
		(pad "S" smd custom
			(at 0.98425 0.9525)
			(size 0.1905 0.1905)
			(layers "F.Cu" "F.Mask" "F.Paste")
			(net "GND")
			(options
				(clearance outline)
				(anchor circle)
			)
			(primitives
				(gr_poly
					(pts
						(arc
							(start -0.1778 0.5715)
							(mid -0.321484 0.511984)
							(end -0.381 0.3683)
						)
						(arc
							(start -0.381 -0.3683)
							(mid -0.321484 -0.511984)
							(end -0.1778 -0.5715)
						)
						(arc
							(start 0.1778 -0.5715)
							(mid 0.321484 -0.511984)
							(end 0.381 -0.3683)
						)
						(arc
							(start 0.381 0.3683)
							(mid 0.321484 0.511984)
							(end 0.1778 0.5715)
						)
					)
					(width 0)
					(fill yes)
				)
			)
		)
	)
	(footprint ""
		(layer "F.Cu")
		(at 27.0764 -168.1988 -90)
		(property "Reference" "R164"
			(at 0 0 270)
			(layer "F.SilkS")
			(hide yes)
			(effects
				(font
					(size 1.27 1.27)
				)
			)
		)
		(property "Value" "0R2J-2-GP"
			(at 0.064008 -3.993896 270)
			(unlocked yes)
			(layer "F.Fab")
			(hide yes)
			(effects
				(font
					(size 1.016 1.016)
					(thickness 0.1524)
				)
			)
		)
		(property "Device Type" "R402H16"
			(at 0.064008 -5.517896 270)
			(unlocked yes)
			(layer "F.Fab")
			(hide yes)
			(effects
				(font
					(size 1.016 1.016)
					(thickness 0.1524)
				)
			)
		)
		(duplicate_pad_numbers_are_jumpers no)
		(fp_line
			(start -0.508 -0.9398)
			(end -0.508 0.9398)
			(stroke
				(width 0.1524)
				(type default)
			)
			(layer "F.SilkS")
		)
		(fp_line
			(start 0.508 -0.9398)
			(end -0.508 -0.9398)
			(stroke
				(width 0.1524)
				(type default)
			)
			(layer "F.SilkS")
		)
		(fp_rect
			(start -0.508 0.9398)
			(end 0.508 -0.9398)
			(stroke
				(width 0)
				(type default)
			)
			(fill no)
			(layer "F.CrtYd")
		)
		(fp_rect
			(start -0.508 0.9398)
			(end 0.508 -0.9398)
			(stroke
				(width 0)
				(type default)
			)
			(fill no)
			(layer "F.Fab")
		)
		(pad "1" smd custom
			(at 0 -0.4445 270)
			(size 0.1397 0.1397)
			(layers "F.Cu" "F.Mask" "F.Paste")
			(net "PWM_BUFFER_IN_FAN3_FAN4")
			(options
				(clearance outline)
				(anchor circle)
			)
			(primitives
				(gr_poly
					(pts
						(arc
							(start -0.1778 -0.2794)
							(mid -0.249642 -0.249642)
							(end -0.2794 -0.1778)
						)
						(arc
							(start -0.2794 0.1778)
							(mid -0.249642 0.249642)
							(end -0.1778 0.2794)
						)
						(arc
							(start 0.1778 0.2794)
							(mid 0.249642 0.249642)
							(end 0.2794 0.1778)
						)
						(arc
							(start 0.2794 -0.1778)
							(mid 0.249642 -0.249642)
							(end 0.1778 -0.2794)
						)
					)
					(width 0)
					(fill yes)
				)
			)
		)
		(pad "2" smd custom
			(at 0 0.4445 270)
			(size 0.1397 0.1397)
			(layers "F.Cu" "F.Mask" "F.Paste")
			(net "PWM_BUFFER_IN_FAN5_FAN6")
			(options
				(clearance outline)
				(anchor circle)
			)
			(primitives
				(gr_poly
					(pts
						(arc
							(start -0.1778 -0.2794)
							(mid -0.249642 -0.249642)
							(end -0.2794 -0.1778)
						)
						(arc
							(start -0.2794 0.1778)
							(mid -0.249642 0.249642)
							(end -0.1778 0.2794)
						)
						(arc
							(start 0.1778 0.2794)
							(mid 0.249642 0.249642)
							(end 0.2794 0.1778)
						)
						(arc
							(start 0.2794 -0.1778)
							(mid 0.249642 -0.249642)
							(end 0.1778 -0.2794)
						)
					)
					(width 0)
					(fill yes)
				)
			)
		)
	)
	(footprint ""
		(layer "F.Cu")
		(at 30.3022 -253.8984 180)
		(property "Reference" "R46"
			(at 0 0 180)
			(layer "F.SilkS")
			(hide yes)
			(effects
				(font
					(size 1.27 1.27)
				)
			)
		)
		(property "Value" "0R2J-2-GP"
			(at 0.064008 -3.993896 180)
			(unlocked yes)
			(layer "F.Fab")
			(hide yes)
			(effects
				(font
					(size 1.016 1.016)
					(thickness 0.1524)
				)
			)
		)
		(property "Device Type" "R402H16"
			(at 0.064008 -5.517896 180)
			(unlocked yes)
			(layer "F.Fab")
			(hide yes)
			(effects
				(font
					(size 1.016 1.016)
					(thickness 0.1524)
				)
			)
		)
		(duplicate_pad_numbers_are_jumpers no)
		(fp_line
			(start 0.508 -0.9398)
			(end -0.508 -0.9398)
			(stroke
				(width 0.1524)
				(type default)
			)
			(layer "F.SilkS")
		)
		(fp_line
			(start -0.508 -0.9398)
			(end -0.508 0.9398)
			(stroke
				(width 0.1524)
				(type default)
			)
			(layer "F.SilkS")
		)
		(fp_rect
			(start -0.508 0.9398)
			(end 0.508 -0.9398)
			(stroke
				(width 0)
				(type default)
			)
			(fill no)
			(layer "F.CrtYd")
		)
		(fp_rect
			(start -0.508 0.9398)
			(end 0.508 -0.9398)
			(stroke
				(width 0)
				(type default)
			)
			(fill no)
			(layer "F.Fab")
		)
		(pad "1" smd custom
			(at 0 -0.4445 180)
			(size 0.1397 0.1397)
			(layers "F.Cu" "F.Mask" "F.Paste")
			(net "I2C_C_SCL_EEPROM")
			(options
				(clearance outline)
				(anchor circle)
			)
			(primitives
				(gr_poly
					(pts
						(arc
							(start -0.1778 -0.2794)
							(mid -0.249642 -0.249642)
							(end -0.2794 -0.1778)
						)
						(arc
							(start -0.2794 0.1778)
							(mid -0.249642 0.249642)
							(end -0.1778 0.2794)
						)
						(arc
							(start 0.1778 0.2794)
							(mid 0.249642 0.249642)
							(end 0.2794 0.1778)
						)
						(arc
							(start 0.2794 -0.1778)
							(mid 0.249642 -0.249642)
							(end 0.1778 -0.2794)
						)
					)
					(width 0)
					(fill yes)
				)
			)
		)
		(pad "2" smd custom
			(at 0 0.4445 180)
			(size 0.1397 0.1397)
			(layers "F.Cu" "F.Mask" "F.Paste")
			(net "I2C_C_SCL")
			(options
				(clearance outline)
				(anchor circle)
			)
			(primitives
				(gr_poly
					(pts
						(arc
							(start -0.1778 -0.2794)
							(mid -0.249642 -0.249642)
							(end -0.2794 -0.1778)
						)
						(arc
							(start -0.2794 0.1778)
							(mid -0.249642 0.249642)
							(end -0.1778 0.2794)
						)
						(arc
							(start 0.1778 0.2794)
							(mid 0.249642 0.249642)
							(end 0.2794 0.1778)
						)
						(arc
							(start 0.2794 -0.1778)
							(mid 0.249642 -0.249642)
							(end 0.1778 -0.2794)
						)
					)
					(width 0)
					(fill yes)
				)
			)
		)
	)
)
